(kicad_pcb
	(version 20260206)
	(generator "pcbnew")
	(generator_version "10.0")
	(general
		(thickness 1.6)
		(legacy_teardrops no)
	)
	(paper "A4")
	(title_block
		(title "baseboard — 13948-1b.1110WZS1818.brd")
		(comment 1 "Honey Badger (Wiwynn) / footprints 1109-1116 of 2523")
	)
	(layers
		(0 "F.Cu" signal "TOP")
		(4 "In1.Cu" signal "L2GND")
		(6 "In2.Cu" signal "L3")
		(8 "In3.Cu" signal "L4VCC")
		(10 "In4.Cu" signal "L5VCC")
		(12 "In5.Cu" signal "L6")
		(14 "In6.Cu" signal "L7GND")
		(2 "B.Cu" signal "BOTTOM")
		(9 "F.Adhes" user "F.Adhesive")
		(11 "B.Adhes" user "B.Adhesive")
		(13 "F.Paste" user "Package Geometry/Pastemask Top")
		(15 "B.Paste" user "Package Geometry/Pastemask Bottom")
		(5 "F.SilkS" user "Ref Des/Silkscreen Top")
		(7 "B.SilkS" user "Ref Des/Silkscreen Bottom")
		(1 "F.Mask" user "Board Geometry/Soldermask Top")
		(3 "B.Mask" user "Board Geometry/Soldermask Bottom")
		(17 "Dwgs.User" user "User.Drawings")
		(19 "Cmts.User" user "User.Comments")
		(21 "Eco1.User" user "User.Eco1")
		(23 "Eco2.User" user "User.Eco2")
		(25 "Edge.Cuts" user "Board Geometry/Outline")
		(27 "Margin" user)
		(31 "F.CrtYd" user "Package Geometry/Place Bound Top")
		(29 "B.CrtYd" user "Package Geometry/Place Bound Bottom")
		(35 "F.Fab" user "Ref Des/Assembly Top")
		(33 "B.Fab" user "Ref Des/Assembly Bottom")
	)
	(footprint ""
		(layer "F.Cu")
		(at 82.43697 -129.159)
		(property "Reference" "SC307"
			(at 0 0 0)
			(layer "F.SilkS")
			(hide yes)
			(effects
				(font
					(size 1.27 1.27)
				)
			)
		)
		(property "Value" "SCD1U16V2KX-3GP"
			(at 1.1811 -2.7051 0)
			(unlocked yes)
			(layer "F.Fab")
			(hide yes)
			(effects
				(font
					(size 1.016 1.016)
					(thickness 0.1524)
				)
			)
		)
		(property "Device Type" "C402H22"
			(at 1.1811 -4.2291 0)
			(unlocked yes)
			(layer "F.Fab")
			(hide yes)
			(effects
				(font
					(size 1.016 1.016)
					(thickness 0.1524)
				)
			)
		)
		(duplicate_pad_numbers_are_jumpers no)
		(fp_rect
			(start -0.4318 0.9525)
			(end 0.4318 -0.9525)
			(stroke
				(width 0)
				(type default)
			)
			(fill no)
			(layer "F.CrtYd")
		)
		(fp_rect
			(start -0.4318 0.9525)
			(end 0.4318 -0.9525)
			(stroke
				(width 0)
				(type default)
			)
			(fill no)
			(layer "F.Fab")
		)
		(pad "1" smd custom
			(at 0 -0.4445)
			(size 0.1524 0.1524)
			(layers "F.Cu" "F.Mask" "F.Paste")
			(net "P1V8_E")
			(options
				(clearance outline)
				(anchor circle)
			)
			(primitives
				(gr_poly
					(pts
						(arc
							(start 0.3048 -0.2032)
							(mid 0.275042 -0.275042)
							(end 0.2032 -0.3048)
						)
						(arc
							(start -0.2032 -0.3048)
							(mid -0.275042 -0.275042)
							(end -0.3048 -0.2032)
						)
						(arc
							(start -0.3048 0.2032)
							(mid -0.275042 0.275042)
							(end -0.2032 0.3048)
						)
						(arc
							(start 0.2032 0.3048)
							(mid 0.275042 0.275042)
							(end 0.3048 0.2032)
						)
					)
					(width 0)
					(fill yes)
				)
			)
		)
		(pad "2" smd custom
			(at 0 0.4445)
			(size 0.1524 0.1524)
			(layers "F.Cu" "F.Mask" "F.Paste")
			(net "GND")
			(options
				(clearance outline)
				(anchor circle)
			)
			(primitives
				(gr_poly
					(pts
						(arc
							(start 0.3048 -0.2032)
							(mid 0.275042 -0.275042)
							(end 0.2032 -0.3048)
						)
						(arc
							(start -0.2032 -0.3048)
							(mid -0.275042 -0.275042)
							(end -0.3048 -0.2032)
						)
						(arc
							(start -0.3048 0.2032)
							(mid -0.275042 0.275042)
							(end -0.2032 0.3048)
						)
						(arc
							(start 0.2032 0.3048)
							(mid 0.275042 0.275042)
							(end 0.3048 0.2032)
						)
					)
					(width 0)
					(fill yes)
				)
			)
		)
	)
	(footprint ""
		(layer "F.Cu")
		(at 107.07497 -114.3 180)
		(property "Reference" "SC1084"
			(at 0 0 180)
			(layer "F.SilkS")
			(hide yes)
			(effects
				(font
					(size 1.27 1.27)
				)
			)
		)
		(property "Value" "SCD01U10V1KX-GP"
			(at -2.8321 -1.7399 180)
			(unlocked yes)
			(layer "F.Fab")
			(hide yes)
			(effects
				(font
					(size 1.016 1.016)
					(thickness 0.1524)
				)
			)
		)
		(property "Device Type" "C0201H13"
			(at -2.8321 -3.2639 180)
			(unlocked yes)
			(layer "F.Fab")
			(hide yes)
			(effects
				(font
					(size 1.016 1.016)
					(thickness 0.1524)
				)
			)
		)
		(duplicate_pad_numbers_are_jumpers no)
		(fp_rect
			(start -0.2794 0.6477)
			(end 0.2794 -0.6477)
			(stroke
				(width 0)
				(type default)
			)
			(fill no)
			(layer "F.CrtYd")
		)
		(fp_rect
			(start -0.2794 0.6477)
			(end 0.2794 -0.6477)
			(stroke
				(width 0)
				(type default)
			)
			(fill no)
			(layer "F.Fab")
		)
		(pad "1" smd custom
			(at 0 -0.2794 180)
			(size 0.0762 0.0762)
			(layers "F.Cu" "F.Mask" "F.Paste")
			(net "SAS_HDD_TX8_N")
			(options
				(clearance outline)
				(anchor circle)
			)
			(primitives
				(gr_poly
					(pts
						(arc
							(start 0.1524 -0.127)
							(mid 0.137521 -0.162921)
							(end 0.1016 -0.1778)
						)
						(arc
							(start -0.1016 -0.1778)
							(mid -0.137521 -0.162921)
							(end -0.1524 -0.127)
						)
						(arc
							(start -0.1524 0.127)
							(mid -0.137521 0.162921)
							(end -0.1016 0.1778)
						)
						(arc
							(start 0.1016 0.1778)
							(mid 0.137521 0.162921)
							(end 0.1524 0.127)
						)
					)
					(width 0)
					(fill yes)
				)
			)
		)
		(pad "2" smd custom
			(at 0 0.2794 180)
			(size 0.0762 0.0762)
			(layers "F.Cu" "F.Mask" "F.Paste")
			(net "SAS_EXP_GF_TX_DN12")
			(options
				(clearance outline)
				(anchor circle)
			)
			(primitives
				(gr_poly
					(pts
						(arc
							(start 0.1524 -0.127)
							(mid 0.137521 -0.162921)
							(end 0.1016 -0.1778)
						)
						(arc
							(start -0.1016 -0.1778)
							(mid -0.137521 -0.162921)
							(end -0.1524 -0.127)
						)
						(arc
							(start -0.1524 0.127)
							(mid -0.137521 0.162921)
							(end -0.1016 0.1778)
						)
						(arc
							(start 0.1016 0.1778)
							(mid 0.137521 0.162921)
							(end 0.1524 0.127)
						)
					)
					(width 0)
					(fill yes)
				)
			)
		)
	)
	(footprint ""
		(layer "F.Cu")
		(at 274.193 -184.531 90)
		(property "Reference" "R358"
			(at 0 0 90)
			(layer "F.SilkS")
			(hide yes)
			(effects
				(font
					(size 1.27 1.27)
				)
			)
		)
		(property "Value" "3K3R2F-2-GP"
			(at 0.064008 -3.993896 90)
			(unlocked yes)
			(layer "F.Fab")
			(hide yes)
			(effects
				(font
					(size 1.016 1.016)
					(thickness 0.1524)
				)
			)
		)
		(property "Device Type" "R402H16"
			(at 0.064008 -5.517896 90)
			(unlocked yes)
			(layer "F.Fab")
			(hide yes)
			(effects
				(font
					(size 1.016 1.016)
					(thickness 0.1524)
				)
			)
		)
		(duplicate_pad_numbers_are_jumpers no)
		(fp_line
			(start 0.508 -0.9398)
			(end -0.508 -0.9398)
			(stroke
				(width 0.1524)
				(type default)
			)
			(layer "F.SilkS")
		)
		(fp_line
			(start -0.508 -0.9398)
			(end -0.508 0.9398)
			(stroke
				(width 0.1524)
				(type default)
			)
			(layer "F.SilkS")
		)
		(fp_rect
			(start -0.508 0.9398)
			(end 0.508 -0.9398)
			(stroke
				(width 0)
				(type default)
			)
			(fill no)
			(layer "F.CrtYd")
		)
		(fp_rect
			(start -0.508 0.9398)
			(end 0.508 -0.9398)
			(stroke
				(width 0)
				(type default)
			)
			(fill no)
			(layer "F.Fab")
		)
		(pad "1" smd custom
			(at 0 -0.4445 90)
			(size 0.1397 0.1397)
			(layers "F.Cu" "F.Mask" "F.Paste")
			(net "P3V3_STBY")
			(options
				(clearance outline)
				(anchor circle)
			)
			(primitives
				(gr_poly
					(pts
						(arc
							(start -0.1778 -0.2794)
							(mid -0.249642 -0.249642)
							(end -0.2794 -0.1778)
						)
						(arc
							(start -0.2794 0.1778)
							(mid -0.249642 0.249642)
							(end -0.1778 0.2794)
						)
						(arc
							(start 0.1778 0.2794)
							(mid 0.249642 0.249642)
							(end 0.2794 0.1778)
						)
						(arc
							(start 0.2794 -0.1778)
							(mid 0.249642 -0.249642)
							(end 0.1778 -0.2794)
						)
					)
					(width 0)
					(fill yes)
				)
			)
		)
		(pad "2" smd custom
			(at 0 0.4445 90)
			(size 0.1397 0.1397)
			(layers "F.Cu" "F.Mask" "F.Paste")
			(net "ROMD4")
			(options
				(clearance outline)
				(anchor circle)
			)
			(primitives
				(gr_poly
					(pts
						(arc
							(start -0.1778 -0.2794)
							(mid -0.249642 -0.249642)
							(end -0.2794 -0.1778)
						)
						(arc
							(start -0.2794 0.1778)
							(mid -0.249642 0.249642)
							(end -0.1778 0.2794)
						)
						(arc
							(start 0.1778 0.2794)
							(mid 0.249642 0.249642)
							(end 0.2794 0.1778)
						)
						(arc
							(start 0.2794 -0.1778)
							(mid 0.249642 -0.249642)
							(end 0.1778 -0.2794)
						)
					)
					(width 0)
					(fill yes)
				)
			)
		)
	)
	(footprint ""
		(layer "F.Cu")
		(at 187.198 -22.86)
		(property "Reference" "TP130"
			(at 0 0 0)
			(layer "F.SilkS")
			(hide yes)
			(effects
				(font
					(size 1.27 1.27)
				)
			)
		)
		(property "Value" "TPAD28"
			(at 0.0127 -1.8034 0)
			(unlocked yes)
			(layer "F.Fab")
			(hide yes)
			(effects
				(font
					(size 1.016 1.016)
					(thickness 0.1524)
				)
			)
		)
		(property "Device Type" "TPAD28"
			(at 0.0127 -3.3274 0)
			(unlocked yes)
			(layer "F.Fab")
			(hide yes)
			(effects
				(font
					(size 1.016 1.016)
					(thickness 0.1524)
				)
			)
		)
		(duplicate_pad_numbers_are_jumpers no)
		(fp_poly
			(pts
				(arc
					(start 0.3556 0)
					(mid -0.3556 0)
					(end 0.3556 0)
				)
			)
			(stroke
				(width 0)
				(type default)
			)
			(fill no)
			(layer "F.CrtYd")
		)
		(fp_poly
			(pts
				(arc
					(start 0.6096 0)
					(mid -0.6096 0)
					(end 0.6096 0)
				)
			)
			(stroke
				(width 0)
				(type default)
			)
			(fill no)
			(layer "F.Fab")
		)
		(pad "1" smd circle
			(at 0 0)
			(size 0.7112 0.7112)
			(layers "F.Cu" "F.Mask" "F.Paste")
			(net "RMII_BMC_MDC_R")
		)
	)
	(footprint ""
		(layer "F.Cu")
		(at 48.514 -221.996 -90)
		(property "Reference" "C7316"
			(at 0 0 270)
			(layer "F.SilkS")
			(hide yes)
			(effects
				(font
					(size 1.27 1.27)
				)
			)
		)
		(property "Value" "SCD1U25V3JX-GP"
			(at 0 -2.8194 270)
			(unlocked yes)
			(layer "F.Fab")
			(hide yes)
			(effects
				(font
					(size 1.016 1.016)
					(thickness 0.1524)
				)
			)
		)
		(property "Device Type" "C603H36"
			(at 0 -4.3434 270)
			(unlocked yes)
			(layer "F.Fab")
			(hide yes)
			(effects
				(font
					(size 1.016 1.016)
					(thickness 0.1524)
				)
			)
		)
		(duplicate_pad_numbers_are_jumpers no)
		(fp_line
			(start 0.508 0)
			(end -0.508 0)
			(stroke
				(width 0.2032)
				(type default)
			)
			(layer "F.SilkS")
		)
		(fp_rect
			(start -0.5842 1.3335)
			(end 0.5842 -1.3335)
			(stroke
				(width 0)
				(type default)
			)
			(fill no)
			(layer "F.CrtYd")
		)
		(fp_rect
			(start -0.5842 1.3335)
			(end 0.5842 -1.3335)
			(stroke
				(width 0)
				(type default)
			)
			(fill no)
			(layer "F.Fab")
		)
		(pad "1" smd custom
			(at 0 -0.762 270)
			(size 0.2159 0.2159)
			(layers "F.Cu" "F.Mask" "F.Paste")
			(net "MB0_PSET_R")
			(options
				(clearance outline)
				(anchor circle)
			)
			(primitives
				(gr_poly
					(pts
						(arc
							(start -0.3302 -0.4318)
							(mid -0.402042 -0.402042)
							(end -0.4318 -0.3302)
						)
						(arc
							(start -0.4318 0.3302)
							(mid -0.402042 0.402042)
							(end -0.3302 0.4318)
						)
						(arc
							(start 0.3302 0.4318)
							(mid 0.402042 0.402042)
							(end 0.4318 0.3302)
						)
						(arc
							(start 0.4318 -0.3302)
							(mid 0.402042 -0.402042)
							(end 0.3302 -0.4318)
						)
					)
					(width 0)
					(fill yes)
				)
			)
		)
		(pad "2" smd custom
			(at 0 0.762 270)
			(size 0.2159 0.2159)
			(layers "F.Cu" "F.Mask" "F.Paste")
			(net "AGND_CURRENT_MON")
			(options
				(clearance outline)
				(anchor circle)
			)
			(primitives
				(gr_poly
					(pts
						(arc
							(start -0.3302 -0.4318)
							(mid -0.402042 -0.402042)
							(end -0.4318 -0.3302)
						)
						(arc
							(start -0.4318 0.3302)
							(mid -0.402042 0.402042)
							(end -0.3302 0.4318)
						)
						(arc
							(start 0.3302 0.4318)
							(mid 0.402042 0.402042)
							(end 0.4318 0.3302)
						)
						(arc
							(start 0.4318 -0.3302)
							(mid 0.402042 -0.402042)
							(end 0.3302 -0.4318)
						)
					)
					(width 0)
					(fill yes)
				)
			)
		)
	)
	(footprint ""
		(layer "F.Cu")
		(at 23.064216 -204.90688 90)
		(property "Reference" "R567"
			(at 0 0 90)
			(layer "F.SilkS")
			(hide yes)
			(effects
				(font
					(size 1.27 1.27)
				)
			)
		)
		(property "Value" "4K7R2F-GP"
			(at 0.064008 -3.993896 90)
			(unlocked yes)
			(layer "F.Fab")
			(hide yes)
			(effects
				(font
					(size 1.016 1.016)
					(thickness 0.1524)
				)
			)
		)
		(property "Device Type" "R402H16"
			(at 0.064008 -5.517896 90)
			(unlocked yes)
			(layer "F.Fab")
			(hide yes)
			(effects
				(font
					(size 1.016 1.016)
					(thickness 0.1524)
				)
			)
		)
		(duplicate_pad_numbers_are_jumpers no)
		(fp_line
			(start 0.508 -0.9398)
			(end -0.508 -0.9398)
			(stroke
				(width 0.1524)
				(type default)
			)
			(layer "F.SilkS")
		)
		(fp_line
			(start -0.508 -0.9398)
			(end -0.508 0.9398)
			(stroke
				(width 0.1524)
				(type default)
			)
			(layer "F.SilkS")
		)
		(fp_rect
			(start -0.508 0.9398)
			(end 0.508 -0.9398)
			(stroke
				(width 0)
				(type default)
			)
			(fill no)
			(layer "F.CrtYd")
		)
		(fp_rect
			(start -0.508 0.9398)
			(end 0.508 -0.9398)
			(stroke
				(width 0)
				(type default)
			)
			(fill no)
			(layer "F.Fab")
		)
		(pad "1" smd custom
			(at 0 -0.4445 90)
			(size 0.1397 0.1397)
			(layers "F.Cu" "F.Mask" "F.Paste")
			(net "P3V3_STBY")
			(options
				(clearance outline)
				(anchor circle)
			)
			(primitives
				(gr_poly
					(pts
						(arc
							(start -0.1778 -0.2794)
							(mid -0.249642 -0.249642)
							(end -0.2794 -0.1778)
						)
						(arc
							(start -0.2794 0.1778)
							(mid -0.249642 0.249642)
							(end -0.1778 0.2794)
						)
						(arc
							(start 0.1778 0.2794)
							(mid 0.249642 0.249642)
							(end 0.2794 0.1778)
						)
						(arc
							(start 0.2794 -0.1778)
							(mid 0.249642 -0.249642)
							(end 0.1778 -0.2794)
						)
					)
					(width 0)
					(fill yes)
				)
			)
		)
		(pad "2" smd custom
			(at 0 0.4445 90)
			(size 0.1397 0.1397)
			(layers "F.Cu" "F.Mask" "F.Paste")
			(net "VOL_SEN_ALERT_U17")
			(options
				(clearance outline)
				(anchor circle)
			)
			(primitives
				(gr_poly
					(pts
						(arc
							(start -0.1778 -0.2794)
							(mid -0.249642 -0.249642)
							(end -0.2794 -0.1778)
						)
						(arc
							(start -0.2794 0.1778)
							(mid -0.249642 0.249642)
							(end -0.1778 0.2794)
						)
						(arc
							(start 0.1778 0.2794)
							(mid 0.249642 0.249642)
							(end 0.2794 0.1778)
						)
						(arc
							(start 0.2794 -0.1778)
							(mid 0.249642 -0.249642)
							(end 0.1778 -0.2794)
						)
					)
					(width 0)
					(fill yes)
				)
			)
		)
	)
	(footprint ""
		(layer "F.Cu")
		(at 48.387 -225.298 180)
		(property "Reference" "C7275"
			(at 0 0 180)
			(layer "F.SilkS")
			(hide yes)
			(effects
				(font
					(size 1.27 1.27)
				)
			)
		)
		(property "Value" "SC1U16V3KX-5GP"
			(at 0 -2.8194 180)
			(unlocked yes)
			(layer "F.Fab")
			(hide yes)
			(effects
				(font
					(size 1.016 1.016)
					(thickness 0.1524)
				)
			)
		)
		(property "Device Type" "C603H36"
			(at 0 -4.3434 180)
			(unlocked yes)
			(layer "F.Fab")
			(hide yes)
			(effects
				(font
					(size 1.016 1.016)
					(thickness 0.1524)
				)
			)
		)
		(duplicate_pad_numbers_are_jumpers no)
		(fp_line
			(start 0.508 0)
			(end -0.508 0)
			(stroke
				(width 0.2032)
				(type default)
			)
			(layer "F.SilkS")
		)
		(fp_rect
			(start -0.5842 1.3335)
			(end 0.5842 -1.3335)
			(stroke
				(width 0)
				(type default)
			)
			(fill no)
			(layer "F.CrtYd")
		)
		(fp_rect
			(start -0.5842 1.3335)
			(end 0.5842 -1.3335)
			(stroke
				(width 0)
				(type default)
			)
			(fill no)
			(layer "F.Fab")
		)
		(pad "1" smd custom
			(at 0 -0.762 180)
			(size 0.2159 0.2159)
			(layers "F.Cu" "F.Mask" "F.Paste")
			(net "MB0_CM_OV_R")
			(options
				(clearance outline)
				(anchor circle)
			)
			(primitives
				(gr_poly
					(pts
						(arc
							(start -0.3302 -0.4318)
							(mid -0.402042 -0.402042)
							(end -0.4318 -0.3302)
						)
						(arc
							(start -0.4318 0.3302)
							(mid -0.402042 0.402042)
							(end -0.3302 0.4318)
						)
						(arc
							(start 0.3302 0.4318)
							(mid 0.402042 0.402042)
							(end 0.4318 0.3302)
						)
						(arc
							(start 0.4318 -0.3302)
							(mid 0.402042 -0.402042)
							(end 0.3302 -0.4318)
						)
					)
					(width 0)
					(fill yes)
				)
			)
		)
		(pad "2" smd custom
			(at 0 0.762 180)
			(size 0.2159 0.2159)
			(layers "F.Cu" "F.Mask" "F.Paste")
			(net "AGND_CURRENT_MON")
			(options
				(clearance outline)
				(anchor circle)
			)
			(primitives
				(gr_poly
					(pts
						(arc
							(start -0.3302 -0.4318)
							(mid -0.402042 -0.402042)
							(end -0.4318 -0.3302)
						)
						(arc
							(start -0.4318 0.3302)
							(mid -0.402042 0.402042)
							(end -0.3302 0.4318)
						)
						(arc
							(start 0.3302 0.4318)
							(mid 0.402042 0.402042)
							(end 0.4318 0.3302)
						)
						(arc
							(start 0.4318 -0.3302)
							(mid 0.402042 -0.402042)
							(end 0.3302 -0.4318)
						)
					)
					(width 0)
					(fill yes)
				)
			)
		)
	)
	(footprint ""
		(layer "F.Cu")
		(at 86.49716 -42.926 -90)
		(property "Reference" "SC890"
			(at 0 0 270)
			(layer "F.SilkS")
			(hide yes)
			(effects
				(font
					(size 1.27 1.27)
				)
			)
		)
		(property "Value" "SCD01U10V1KX-GP"
			(at -2.8321 -1.7399 270)
			(unlocked yes)
			(layer "F.Fab")
			(hide yes)
			(effects
				(font
					(size 1.016 1.016)
					(thickness 0.1524)
				)
			)
		)
		(property "Device Type" "C0201H13"
			(at -2.8321 -3.2639 270)
			(unlocked yes)
			(layer "F.Fab")
			(hide yes)
			(effects
				(font
					(size 1.016 1.016)
					(thickness 0.1524)
				)
			)
		)
		(duplicate_pad_numbers_are_jumpers no)
		(fp_rect
			(start -0.2794 0.6477)
			(end 0.2794 -0.6477)
			(stroke
				(width 0)
				(type default)
			)
			(fill no)
			(layer "F.CrtYd")
		)
		(fp_rect
			(start -0.2794 0.6477)
			(end 0.2794 -0.6477)
			(stroke
				(width 0)
				(type default)
			)
			(fill no)
			(layer "F.Fab")
		)
		(pad "1" smd custom
			(at 0 -0.2794 270)
			(size 0.0762 0.0762)
			(layers "F.Cu" "F.Mask" "F.Paste")
			(net "SAS3008_RAID_TX_C_N5")
			(options
				(clearance outline)
				(anchor circle)
			)
			(primitives
				(gr_poly
					(pts
						(arc
							(start 0.1524 -0.127)
							(mid 0.137521 -0.162921)
							(end 0.1016 -0.1778)
						)
						(arc
							(start -0.1016 -0.1778)
							(mid -0.137521 -0.162921)
							(end -0.1524 -0.127)
						)
						(arc
							(start -0.1524 0.127)
							(mid -0.137521 0.162921)
							(end -0.1016 0.1778)
						)
						(arc
							(start 0.1016 0.1778)
							(mid 0.137521 0.162921)
							(end 0.1524 0.127)
						)
					)
					(width 0)
					(fill yes)
				)
			)
		)
		(pad "2" smd custom
			(at 0 0.2794 270)
			(size 0.0762 0.0762)
			(layers "F.Cu" "F.Mask" "F.Paste")
			(net "IOC_RAID_TX_N5")
			(options
				(clearance outline)
				(anchor circle)
			)
			(primitives
				(gr_poly
					(pts
						(arc
							(start 0.1524 -0.127)
							(mid 0.137521 -0.162921)
							(end 0.1016 -0.1778)
						)
						(arc
							(start -0.1016 -0.1778)
							(mid -0.137521 -0.162921)
							(end -0.1524 -0.127)
						)
						(arc
							(start -0.1524 0.127)
							(mid -0.137521 0.162921)
							(end -0.1016 0.1778)
						)
						(arc
							(start 0.1016 0.1778)
							(mid 0.137521 0.162921)
							(end 0.1524 0.127)
						)
					)
					(width 0)
					(fill yes)
				)
			)
		)
	)
)
